# T6G (Grand Teton) — schematic netlist excerpt (pin names and nets, part order shuffled) for the footprints in the layout excerpt that follows; sources: Cadence DE-HDL packaged netlist, KiCad conversion of 04192023_DAF0TMB3IC0_F0TG_MB_C_brd_V02_OCP.brd

R366  Q_RES  1K 1% CHIP  pkg 0402LF  page 161 : A = PVDD18_S5_P1 ; B = SMB_CPU1_SEC_SCL
R402  Q_RES  1K 1% CHIP  pkg 0402LF  page 27 : A = PVDD18_S5_P0 ; B = JTAG_CPU0_TMS

(kicad_pcb
	(version 20260206)
	(generator "pcbnew")
	(generator_version "10.0")
	(general
		(thickness 1.6)
		(legacy_teardrops no)
	)
	(paper "A4")
	(title_block
		(title "04192023_DAF0TMB3IC0_F0TG_MB_C_brd_V02_OCP.brd")
		(comment 1 "Grand Teton / footprints 7018-7019 of 8354")
	)
	(layers
		(0 "F.Cu" signal "TOP")
		(4 "In1.Cu" signal "GND")
		(6 "In2.Cu" signal "IN1")
		(8 "In3.Cu" signal "GND1")
		(10 "In4.Cu" signal "IN2")
		(12 "In5.Cu" signal "GND2")
		(14 "In6.Cu" signal "IN3")
		(16 "In7.Cu" signal "GND3")
		(18 "In8.Cu" signal "VCC")
		(20 "In9.Cu" signal "VCC1")
		(22 "In10.Cu" signal "GND4")
		(24 "In11.Cu" signal "IN4")
		(26 "In12.Cu" signal "GND5")
		(28 "In13.Cu" signal "IN5")
		(30 "In14.Cu" signal "GND6")
		(32 "In15.Cu" signal "IN6")
		(34 "In16.Cu" signal "GND7")
		(2 "B.Cu" signal "BOTTOM")
		(9 "F.Adhes" user "F.Adhesive")
		(11 "B.Adhes" user "B.Adhesive")
		(13 "F.Paste" user "Package Geometry/Pastemask Top")
		(15 "B.Paste" user "Package Geometry/Pastemask Bottom")
		(5 "F.SilkS" user "Ref Des/Silkscreen Top")
		(7 "B.SilkS" user "Ref Des/Silkscreen Bottom")
		(1 "F.Mask" user "Board Geometry/Soldermask Top")
		(3 "B.Mask" user "Board Geometry/Soldermask Bottom")
		(17 "Dwgs.User" user "User.Drawings")
		(19 "Cmts.User" user "User.Comments")
		(21 "Eco1.User" user "User.Eco1")
		(23 "Eco2.User" user "User.Eco2")
		(25 "Edge.Cuts" user "Board Geometry/Outline")
		(27 "Margin" user)
		(31 "F.CrtYd" user "Package Geometry/Place Bound Top")
		(29 "B.CrtYd" user "Package Geometry/Place Bound Bottom")
		(35 "F.Fab" user "Ref Des/Assembly Top")
		(33 "B.Fab" user "Ref Des/Assembly Bottom")
	)
	(footprint ""
		(layer "B.Cu")
		(at 378.504958 -208.530952 -90)
		(property "Reference" "R402"
			(at 0 0 90)
			(layer "B.SilkS")
			(hide yes)
			(effects
				(font
					(size 1.27 1.27)
				)
				(justify mirror)
			)
		)
		(property "Value" ""
			(at 0 0 90)
			(layer "B.Fab")
			(effects
				(font
					(size 1.27 1.27)
				)
				(justify mirror)
			)
		)
		(duplicate_pad_numbers_are_jumpers no)
		(fp_line
			(start -0.7874 0.4064)
			(end 0.7874 0.4064)
			(stroke
				(width 0.1524)
				(type default)
			)
			(layer "B.SilkS")
		)
		(fp_line
			(start 0.7874 0.4064)
			(end 0.7874 -0.4064)
			(stroke
				(width 0.1524)
				(type default)
			)
			(layer "B.SilkS")
		)
		(fp_line
			(start -0.7874 -0.4064)
			(end -0.7874 0.4064)
			(stroke
				(width 0.1524)
				(type default)
			)
			(layer "B.SilkS")
		)
		(fp_line
			(start 0.7874 -0.4064)
			(end -0.7874 -0.4064)
			(stroke
				(width 0.1524)
				(type default)
			)
			(layer "B.SilkS")
		)
		(fp_line
			(start -0.67945 0.3048)
			(end -0.120396 0.3048)
			(stroke
				(width 0.1)
				(type default)
			)
			(layer "B.Fab")
		)
		(fp_line
			(start -0.120396 0.3048)
			(end -0.120396 0.2794)
			(stroke
				(width 0.1)
				(type default)
			)
			(layer "B.Fab")
		)
		(fp_line
			(start 0.12065 0.3048)
			(end 0.67945 0.3048)
			(stroke
				(width 0.1)
				(type default)
			)
			(layer "B.Fab")
		)
		(fp_line
			(start 0.67945 0.3048)
			(end 0.67945 -0.305054)
			(stroke
				(width 0.1)
				(type default)
			)
			(layer "B.Fab")
		)
		(fp_line
			(start -0.120396 0.2794)
			(end 0.12065 0.2794)
			(stroke
				(width 0.1)
				(type default)
			)
			(layer "B.Fab")
		)
		(fp_line
			(start 0.12065 0.2794)
			(end 0.12065 0.3048)
			(stroke
				(width 0.1)
				(type default)
			)
			(layer "B.Fab")
		)
		(fp_line
			(start -0.12065 -0.2794)
			(end -0.12065 -0.3048)
			(stroke
				(width 0.1)
				(type default)
			)
			(layer "B.Fab")
		)
		(fp_line
			(start 0.12065 -0.2794)
			(end -0.12065 -0.2794)
			(stroke
				(width 0.1)
				(type default)
			)
			(layer "B.Fab")
		)
		(fp_line
			(start -0.67945 -0.3048)
			(end -0.67945 0.3048)
			(stroke
				(width 0.1)
				(type default)
			)
			(layer "B.Fab")
		)
		(fp_line
			(start -0.12065 -0.3048)
			(end -0.67945 -0.3048)
			(stroke
				(width 0.1)
				(type default)
			)
			(layer "B.Fab")
		)
		(fp_line
			(start 0.12065 -0.305054)
			(end 0.12065 -0.2794)
			(stroke
				(width 0.1)
				(type default)
			)
			(layer "B.Fab")
		)
		(fp_line
			(start 0.67945 -0.305054)
			(end 0.12065 -0.305054)
			(stroke
				(width 0.1)
				(type default)
			)
			(layer "B.Fab")
		)
		(pad "1" smd circle
			(at 0.40005 0 90)
			(size 0 0)
			(layers "B.Cu" "B.Mask" "B.Paste")
			(net "PVDD18_S5_P0")
		)
		(pad "2" smd circle
			(at -0.40005 0 90)
			(size 0 0)
			(layers "B.Cu" "B.Mask" "B.Paste")
			(net "JTAG_CPU0_TMS")
		)
	)
	(footprint ""
		(layer "B.Cu")
		(at 238.379 -231.648 -90)
		(property "Reference" "R366"
			(at 0 0 90)
			(layer "B.SilkS")
			(hide yes)
			(effects
				(font
					(size 1.27 1.27)
				)
				(justify mirror)
			)
		)
		(property "Value" ""
			(at 0 0 90)
			(layer "B.Fab")
			(effects
				(font
					(size 1.27 1.27)
				)
				(justify mirror)
			)
		)
		(duplicate_pad_numbers_are_jumpers no)
		(fp_line
			(start -0.7874 0.4064)
			(end 0.7874 0.4064)
			(stroke
				(width 0.1524)
				(type default)
			)
			(layer "B.SilkS")
		)
		(fp_line
			(start 0.7874 0.4064)
			(end 0.7874 -0.4064)
			(stroke
				(width 0.1524)
				(type default)
			)
			(layer "B.SilkS")
		)
		(fp_line
			(start -0.7874 -0.4064)
			(end -0.7874 0.4064)
			(stroke
				(width 0.1524)
				(type default)
			)
			(layer "B.SilkS")
		)
		(fp_line
			(start 0.7874 -0.4064)
			(end -0.7874 -0.4064)
			(stroke
				(width 0.1524)
				(type default)
			)
			(layer "B.SilkS")
		)
		(fp_line
			(start -0.67945 0.3048)
			(end -0.120396 0.3048)
			(stroke
				(width 0.1)
				(type default)
			)
			(layer "B.Fab")
		)
		(fp_line
			(start -0.120396 0.3048)
			(end -0.120396 0.2794)
			(stroke
				(width 0.1)
				(type default)
			)
			(layer "B.Fab")
		)
		(fp_line
			(start 0.12065 0.3048)
			(end 0.67945 0.3048)
			(stroke
				(width 0.1)
				(type default)
			)
			(layer "B.Fab")
		)
		(fp_line
			(start 0.67945 0.3048)
			(end 0.67945 -0.305054)
			(stroke
				(width 0.1)
				(type default)
			)
			(layer "B.Fab")
		)
		(fp_line
			(start -0.120396 0.2794)
			(end 0.12065 0.2794)
			(stroke
				(width 0.1)
				(type default)
			)
			(layer "B.Fab")
		)
		(fp_line
			(start 0.12065 0.2794)
			(end 0.12065 0.3048)
			(stroke
				(width 0.1)
				(type default)
			)
			(layer "B.Fab")
		)
		(fp_line
			(start -0.12065 -0.2794)
			(end -0.12065 -0.3048)
			(stroke
				(width 0.1)
				(type default)
			)
			(layer "B.Fab")
		)
		(fp_line
			(start 0.12065 -0.2794)
			(end -0.12065 -0.2794)
			(stroke
				(width 0.1)
				(type default)
			)
			(layer "B.Fab")
		)
		(fp_line
			(start -0.67945 -0.3048)
			(end -0.67945 0.3048)
			(stroke
				(width 0.1)
				(type default)
			)
			(layer "B.Fab")
		)
		(fp_line
			(start -0.12065 -0.3048)
			(end -0.67945 -0.3048)
			(stroke
				(width 0.1)
				(type default)
			)
			(layer "B.Fab")
		)
		(fp_line
			(start 0.12065 -0.305054)
			(end 0.12065 -0.2794)
			(stroke
				(width 0.1)
				(type default)
			)
			(layer "B.Fab")
		)
		(fp_line
			(start 0.67945 -0.305054)
			(end 0.12065 -0.305054)
			(stroke
				(width 0.1)
				(type default)
			)
			(layer "B.Fab")
		)
		(pad "1" smd circle
			(at 0.40005 0 90)
			(size 0 0)
			(layers "B.Cu" "B.Mask" "B.Paste")
			(net "PVDD18_S5_P1")
		)
		(pad "2" smd circle
			(at -0.40005 0 90)
			(size 0 0)
			(layers "B.Cu" "B.Mask" "B.Paste")
			(net "SMB_CPU1_SEC_SCL")
		)
	)
)
